(kicad_pcb
	(version 20260206)
	(generator "pcbnew")
	(generator_version "10.0")
	(general
		(thickness 1.6)
		(legacy_teardrops no)
	)
	(paper "A4")
	(title_block
		(title "04192023_DAF0TMB3IC0_F0TG_MB_C_brd_V02_OCP.brd")
		(comment 1 "Grand Teton / footprint 1669 of 8354 (U18), pads 105-209 of 484")
	)
	(layers
		(0 "F.Cu" signal "TOP")
		(4 "In1.Cu" signal "GND")
		(6 "In2.Cu" signal "IN1")
		(8 "In3.Cu" signal "GND1")
		(10 "In4.Cu" signal "IN2")
		(12 "In5.Cu" signal "GND2")
		(14 "In6.Cu" signal "IN3")
		(16 "In7.Cu" signal "GND3")
		(18 "In8.Cu" signal "VCC")
		(20 "In9.Cu" signal "VCC1")
		(22 "In10.Cu" signal "GND4")
		(24 "In11.Cu" signal "IN4")
		(26 "In12.Cu" signal "GND5")
		(28 "In13.Cu" signal "IN5")
		(30 "In14.Cu" signal "GND6")
		(32 "In15.Cu" signal "IN6")
		(34 "In16.Cu" signal "GND7")
		(2 "B.Cu" signal "BOTTOM")
		(9 "F.Adhes" user "F.Adhesive")
		(11 "B.Adhes" user "B.Adhesive")
		(13 "F.Paste" user "Package Geometry/Pastemask Top")
		(15 "B.Paste" user "Package Geometry/Pastemask Bottom")
		(5 "F.SilkS" user "Ref Des/Silkscreen Top")
		(7 "B.SilkS" user "Ref Des/Silkscreen Bottom")
		(1 "F.Mask" user "Board Geometry/Soldermask Top")
		(3 "B.Mask" user "Board Geometry/Soldermask Bottom")
		(17 "Dwgs.User" user "User.Drawings")
		(19 "Cmts.User" user "User.Comments")
		(21 "Eco1.User" user "User.Eco1")
		(23 "Eco2.User" user "User.Eco2")
		(25 "Edge.Cuts" user "Board Geometry/Outline")
		(27 "Margin" user)
		(31 "F.CrtYd" user "Package Geometry/Place Bound Top")
		(29 "B.CrtYd" user "Package Geometry/Place Bound Bottom")
		(35 "F.Fab" user "Ref Des/Assembly Top")
		(33 "B.Fab" user "Ref Des/Assembly Bottom")
	)
	(footprint ""
		(layer "F.Cu")
		(at 185.522108 -115.052856 90)
		(property "Reference" "U18"
			(at -10.68451 -12.951206 0)
			(unlocked yes)
			(layer "F.SilkS")
			(effects
				(font
					(size 0.7874 0.5842)
					(thickness 0.1524)
				)
				(justify left)
			)
		)
		(property "Value" ""
			(at 0 0 90)
			(layer "F.Fab")
			(effects
				(font
					(size 1.27 1.27)
				)
			)
		)
		(duplicate_pad_numbers_are_jumpers no)
		(pad "C17" smd circle
			(at 4.400042 -6.800088 90)
			(size 0.4064 0.4064)
			(layers "F.Cu" "F.Mask" "F.Paste")
			(net "RST_SRST_PLD_BMC_R_N")
		)
		(pad "C18" smd circle
			(at 5.199888 -6.800088 90)
			(size 0.4064 0.4064)
			(layers "F.Cu" "F.Mask" "F.Paste")
			(net "FM_OCP_V3_2_AUX_PWR_EN")
		)
		(pad "C19" smd circle
			(at 5.999988 -6.800088 90)
			(size 0.4064 0.4064)
			(layers "F.Cu" "F.Mask" "F.Paste")
			(net "CLK_GEN2_BMC_RC_OE_R_N")
		)
		(pad "C20" smd circle
			(at 6.800088 -6.800088 90)
			(size 0.4064 0.4064)
			(layers "F.Cu" "F.Mask" "F.Paste")
			(net "CLK_GEN2_GPU_FPGA_OE_R_N")
		)
		(pad "C21" smd circle
			(at 7.599934 -6.800088 90)
			(size 0.4064 0.4064)
			(layers "F.Cu" "F.Mask" "F.Paste")
			(net "FM_CPU0_SLP_S5_N")
		)
		(pad "C22" smd circle
			(at 8.400034 -6.800088 90)
			(size 0.4064 0.4064)
			(layers "F.Cu" "F.Mask" "F.Paste")
			(net "FM_CPU0_SLP_S3_N")
		)
		(pad "D1" smd circle
			(at -8.400034 -5.999988 90)
			(size 0.4064 0.4064)
			(layers "F.Cu" "F.Mask" "F.Paste")
			(net "FM_SMM_CRASHDUMP_R")
		)
		(pad "D2" smd circle
			(at -7.599934 -5.999988 90)
			(size 0.4064 0.4064)
			(layers "F.Cu" "F.Mask" "F.Paste")
			(net "FM_CPU0_XTRIG_L4")
		)
		(pad "D3" smd circle
			(at -6.800088 -5.999988 90)
			(size 0.4064 0.4064)
			(layers "F.Cu" "F.Mask" "F.Paste")
			(net "FM_CPU1_XTRIG_L4")
		)
		(pad "D4" smd circle
			(at -5.999988 -5.999988 90)
			(size 0.4064 0.4064)
			(layers "F.Cu" "F.Mask" "F.Paste")
			(net "FM_CPU1_XTRIG_L5")
		)
		(pad "D5" smd circle
			(at -5.199888 -5.999988 90)
			(size 0.4064 0.4064)
			(layers "F.Cu" "F.Mask" "F.Paste")
			(net "FM_I3C_CPU1_MUX1_R_SEL")
		)
		(pad "D6" smd circle
			(at -4.400042 -5.999988 90)
			(size 0.4064 0.4064)
			(layers "F.Cu" "F.Mask" "F.Paste")
			(net "SGPIO_SCM_CLK_<0>")
		)
		(pad "D7" smd circle
			(at -3.599942 -5.999988 90)
			(size 0.4064 0.4064)
			(layers "F.Cu" "F.Mask" "F.Paste")
			(net "SGPIO_SCM_LD_<0>")
		)
		(pad "D8" smd circle
			(at -2.800096 -5.999988 90)
			(size 0.4064 0.4064)
			(layers "F.Cu" "F.Mask" "F.Paste")
			(net "SGPIO_OCP_SFF_LD_N")
		)
		(pad "D9" smd circle
			(at -1.999996 -5.999988 90)
			(size 0.4064 0.4064)
			(layers "F.Cu" "F.Mask" "F.Paste")
			(net "OCP_V3_2_MAIN_PWR_EN")
		)
		(pad "D10" smd circle
			(at -1.199896 -5.999988 90)
			(size 0.4064 0.4064)
			(layers "F.Cu" "F.Mask" "F.Paste")
			(net "JTAG_SCM_PLD_TCK")
		)
		(pad "D11" smd circle
			(at -0.40005 -5.999988 90)
			(size 0.4064 0.4064)
			(layers "F.Cu" "F.Mask" "F.Paste")
			(net "JTAG_SCM_TRST_R_N")
		)
		(pad "D12" smd circle
			(at 0.40005 -5.999988 90)
			(size 0.4064 0.4064)
			(layers "F.Cu" "F.Mask" "F.Paste")
			(net "FM_FAN_PWR_EN")
		)
		(pad "D13" smd circle
			(at 1.199896 -5.999988 90)
			(size 0.4064 0.4064)
			(layers "F.Cu" "F.Mask" "F.Paste")
			(net "RST_MB_STBY_N")
		)
		(pad "D14" smd circle
			(at 1.999996 -5.999988 90)
			(size 0.4064 0.4064)
			(layers "F.Cu" "F.Mask" "F.Paste")
			(net "SGPIO_OCP_V3_2_CLK")
		)
		(pad "D15" smd circle
			(at 2.800096 -5.999988 90)
			(size 0.4064 0.4064)
			(layers "F.Cu" "F.Mask" "F.Paste")
			(net "PRSNT_OCP_V3_2_N")
		)
		(pad "D16" smd circle
			(at 3.599942 -5.999988 90)
			(size 0.4064 0.4064)
			(layers "F.Cu" "F.Mask" "F.Paste")
			(net "FPGA_IO3V3_RSVD_1")
		)
		(pad "D17" smd circle
			(at 4.400042 -5.999988 90)
			(size 0.4064 0.4064)
			(layers "F.Cu" "F.Mask" "F.Paste")
			(net "RST_SMB_SWITCH_N")
		)
		(pad "D18" smd circle
			(at 5.199888 -5.999988 90)
			(size 0.4064 0.4064)
			(layers "F.Cu" "F.Mask" "F.Paste")
			(net "SGPIO_SCM_CLK_<1>")
		)
		(pad "D19" smd circle
			(at 5.999988 -5.999988 90)
			(size 0.4064 0.4064)
			(layers "F.Cu" "F.Mask" "F.Paste")
			(net "PWRGD_P0V9_RETIMER_CPU0_R2")
		)
		(pad "D20" smd circle
			(at 6.800088 -5.999988 90)
			(size 0.4064 0.4064)
			(layers "F.Cu" "F.Mask" "F.Paste")
			(net "RST_CPU0_PERST1_R_N")
		)
		(pad "D21" smd circle
			(at 7.599934 -5.999988 90)
			(size 0.4064 0.4064)
			(layers "F.Cu" "F.Mask" "F.Paste")
			(net "FM_CPU1_SLP_S3_N")
		)
		(pad "D22" smd circle
			(at 8.400034 -5.999988 90)
			(size 0.4064 0.4064)
			(layers "F.Cu" "F.Mask" "F.Paste")
			(net "FM_CPU1_SLP_S5_N")
		)
		(pad "E1" smd circle
			(at -8.400034 -5.199888 90)
			(size 0.4064 0.4064)
			(layers "F.Cu" "F.Mask" "F.Paste")
			(net "FM_BMC_TPM_PRES_N_R")
		)
		(pad "E2" smd circle
			(at -7.599934 -5.199888 90)
			(size 0.4064 0.4064)
			(layers "F.Cu" "F.Mask" "F.Paste")
			(net "FM_CPU1_BMC_RST_R_N")
		)
		(pad "E3" smd circle
			(at -6.800088 -5.199888 90)
			(size 0.4064 0.4064)
			(layers "F.Cu" "F.Mask" "F.Paste")
			(net "FM_CPU0_XTRIG_L7")
		)
		(pad "E4" smd circle
			(at -5.999988 -5.199888 90)
			(size 0.4064 0.4064)
			(layers "F.Cu" "F.Mask" "F.Paste")
			(net "FM_CPU0_XTRIG_L6")
		)
		(pad "E5" smd circle
			(at -5.199888 -5.199888 90)
			(size 0.4064 0.4064)
			(layers "F.Cu" "F.Mask" "F.Paste")
			(net "GND")
		)
		(pad "E6" smd circle
			(at -4.400042 -5.199888 90)
			(size 0.4064 0.4064)
			(layers "F.Cu" "F.Mask" "F.Paste")
			(net "FM_I3C_CPU1_MUX1_OE_R_N")
		)
		(pad "E7" smd circle
			(at -3.599942 -5.199888 90)
			(size 0.4064 0.4064)
			(layers "F.Cu" "F.Mask" "F.Paste")
			(net "SGPIO_SCM_DO_<0>")
		)
		(pad "E8" smd circle
			(at -2.800096 -5.199888 90)
			(size 0.4064 0.4064)
			(layers "F.Cu" "F.Mask" "F.Paste")
			(net "JTAG_SCM_PLD_TDI")
		)
		(pad "E9" smd circle
			(at -1.999996 -5.199888 90)
			(size 0.4064 0.4064)
			(layers "F.Cu" "F.Mask" "F.Paste")
			(net "JTAG_SCM_PLD_TDO")
		)
		(pad "E10" smd circle
			(at -1.199896 -5.199888 90)
			(size 0.4064 0.4064)
			(layers "F.Cu" "F.Mask" "F.Paste")
			(net "FM_LED_ACTIVE_E1S_0")
		)
		(pad "E11" smd circle
			(at -0.40005 -5.199888 90)
			(size 0.4064 0.4064)
			(layers "F.Cu" "F.Mask" "F.Paste")
			(net "FM_SYS_THROTTLE_R_N")
		)
		(pad "E12" smd circle
			(at 0.40005 -5.199888 90)
			(size 0.4064 0.4064)
			(layers "F.Cu" "F.Mask" "F.Paste")
			(net "SCM_SYS_PWRBTN_N")
		)
		(pad "E13" smd circle
			(at 1.199896 -5.199888 90)
			(size 0.4064 0.4064)
			(layers "F.Cu" "F.Mask" "F.Paste")
			(net "HP_LVC3_OCP_V3_2_P12V_PWRGD_R")
		)
		(pad "E14" smd circle
			(at 1.999996 -5.199888 90)
			(size 0.4064 0.4064)
			(layers "F.Cu" "F.Mask" "F.Paste")
			(net "CPLD_JTAG_EN")
		)
		(pad "E15" smd circle
			(at 2.800096 -5.199888 90)
			(size 0.4064 0.4064)
			(layers "F.Cu" "F.Mask" "F.Paste")
			(net "CPLD_PROGRAMN")
		)
		(pad "E16" smd circle
			(at 3.599942 -5.199888 90)
			(size 0.4064 0.4064)
			(layers "F.Cu" "F.Mask" "F.Paste")
			(net "FM_LED_PWRGD_PVDDCR_CPU1_P1")
		)
		(pad "E17" smd circle
			(at 4.400042 -5.199888 90)
			(size 0.4064 0.4064)
			(layers "F.Cu" "F.Mask" "F.Paste")
			(net "VIRTUAL_RESEAT_FPGA_R_N")
		)
		(pad "E18" smd circle
			(at 5.199888 -5.199888 90)
			(size 0.4064 0.4064)
			(layers "F.Cu" "F.Mask" "F.Paste")
			(net "GND")
		)
		(pad "E19" smd circle
			(at 5.999988 -5.199888 90)
			(size 0.4064 0.4064)
			(layers "F.Cu" "F.Mask" "F.Paste")
			(net "RST_CPU1_PERST0_R_N")
		)
		(pad "E20" smd circle
			(at 6.800088 -5.199888 90)
			(size 0.4064 0.4064)
			(layers "F.Cu" "F.Mask" "F.Paste")
			(net "PWRGD_P0V9_RETIMER_CPU1_R2")
		)
		(pad "E21" smd circle
			(at 7.599934 -5.199888 90)
			(size 0.4064 0.4064)
			(layers "F.Cu" "F.Mask" "F.Paste")
			(net "RST_RT_CPU1_P0_RESET_R2_N")
		)
		(pad "E22" smd circle
			(at 8.400034 -5.199888 90)
			(size 0.4064 0.4064)
			(layers "F.Cu" "F.Mask" "F.Paste")
			(net "RST_RT_CPU1_P0_PERST_R2_N")
		)
		(pad "F1" smd circle
			(at -8.400034 -4.400042 90)
			(size 0.4064 0.4064)
			(layers "F.Cu" "F.Mask" "F.Paste")
			(net "FM_PVDDCR_CPU0_P0_OCP_N")
		)
		(pad "F2" smd circle
			(at -7.599934 -4.400042 90)
			(size 0.4064 0.4064)
			(layers "F.Cu" "F.Mask" "F.Paste")
			(net "GND")
		)
		(pad "F3" smd circle
			(at -6.800088 -4.400042 90)
			(size 0.4064 0.4064)
			(layers "F.Cu" "F.Mask" "F.Paste")
			(net "P1V8_AUX")
		)
		(pad "F4" smd circle
			(at -5.999988 -4.400042 90)
			(size 0.4064 0.4064)
			(layers "F.Cu" "F.Mask" "F.Paste")
			(net "FM_BMC_READY_R_N")
		)
		(pad "F5" smd circle
			(at -5.199888 -4.400042 90)
			(size 0.4064 0.4064)
			(layers "F.Cu" "F.Mask" "F.Paste")
			(net "IRQ_BMC_SMI_R_N")
		)
		(pad "F6" smd circle
			(at -4.400042 -4.400042 90)
			(size 0.4064 0.4064)
			(layers "F.Cu" "F.Mask" "F.Paste")
			(net "FM_CPU1_XTRIG_L6")
		)
		(pad "F7" smd circle
			(at -3.599942 -4.400042 90)
			(size 0.4064 0.4064)
			(layers "F.Cu" "F.Mask" "F.Paste")
			(net "FM_I3C_CPU0_MUX1_R_SEL")
		)
		(pad "F8" smd circle
			(at -2.800096 -4.400042 90)
			(size 0.4064 0.4064)
			(layers "F.Cu" "F.Mask" "F.Paste")
			(net "PWRGD_PS_PWROK_PLD_ISO_R")
		)
		(pad "F9" smd circle
			(at -1.999996 -4.400042 90)
			(size 0.4064 0.4064)
			(layers "F.Cu" "F.Mask" "F.Paste")
			(net "P12V_OCP_SFF_EN")
		)
		(pad "F10" smd circle
			(at -1.199896 -4.400042 90)
			(size 0.4064 0.4064)
			(layers "F.Cu" "F.Mask" "F.Paste")
			(net "FM_BOARD_BMC_SKU_ID2")
		)
		(pad "F11" smd circle
			(at -0.40005 -4.400042 90)
			(size 0.4064 0.4064)
			(layers "F.Cu" "F.Mask" "F.Paste")
			(net "SMB_CPU0_4_XLTR_R_SDA")
		)
		(pad "F12" smd circle
			(at 0.40005 -4.400042 90)
			(size 0.4064 0.4064)
			(layers "F.Cu" "F.Mask" "F.Paste")
			(net "GPU_3V3IO_RSVD3_FFU_ISO_R")
		)
		(pad "F13" smd circle
			(at 1.199896 -4.400042 90)
			(size 0.4064 0.4064)
			(layers "F.Cu" "F.Mask" "F.Paste")
			(net "FM_UARTSW_MSB_N")
		)
		(pad "F14" smd circle
			(at 1.999996 -4.400042 90)
			(size 0.4064 0.4064)
			(layers "F.Cu" "F.Mask" "F.Paste")
			(net "SCM_SPARE_1")
		)
		(pad "F15" smd circle
			(at 2.800096 -4.400042 90)
			(size 0.4064 0.4064)
			(layers "F.Cu" "F.Mask" "F.Paste")
			(net "OCP_V3_2_P3V3_PLD_R_PWRGD")
		)
		(pad "F16" smd circle
			(at 3.599942 -4.400042 90)
			(size 0.4064 0.4064)
			(layers "F.Cu" "F.Mask" "F.Paste")
			(net "VIRTUAL_RESEAT")
		)
		(pad "F17" smd circle
			(at 4.400042 -4.400042 90)
			(size 0.4064 0.4064)
			(layers "F.Cu" "F.Mask" "F.Paste")
			(net "RST_CPU0_PERST0_R_N")
		)
		(pad "F18" smd circle
			(at 5.199888 -4.400042 90)
			(size 0.4064 0.4064)
			(layers "F.Cu" "F.Mask" "F.Paste")
			(net "TP_SLOT1_CLKREQ_0_R_N")
		)
		(pad "F19" smd circle
			(at 5.999988 -4.400042 90)
			(size 0.4064 0.4064)
			(layers "F.Cu" "F.Mask" "F.Paste")
			(net "FM_CPU0_SYS_RESET_N")
		)
		(pad "F20" smd circle
			(at 6.800088 -4.400042 90)
			(size 0.4064 0.4064)
			(layers "F.Cu" "F.Mask" "F.Paste")
			(net "P1V8_AUX")
		)
		(pad "F21" smd circle
			(at 7.599934 -4.400042 90)
			(size 0.4064 0.4064)
			(layers "F.Cu" "F.Mask" "F.Paste")
			(net "GND")
		)
		(pad "F22" smd circle
			(at 8.400034 -4.400042 90)
			(size 0.4064 0.4064)
			(layers "F.Cu" "F.Mask" "F.Paste")
			(net "FM_CPU1_RSMRST_N")
		)
		(pad "G1" smd circle
			(at -8.400034 -3.599942 90)
			(size 0.4064 0.4064)
			(layers "F.Cu" "F.Mask" "F.Paste")
			(net "FM_CPU1_PROCHOT_R_N")
		)
		(pad "G2" smd circle
			(at -7.599934 -3.599942 90)
			(size 0.4064 0.4064)
			(layers "F.Cu" "F.Mask" "F.Paste")
			(net "FM_PVDDCR_CPU0_P1_OCP_N")
		)
		(pad "G3" smd circle
			(at -6.800088 -3.599942 90)
			(size 0.4064 0.4064)
			(layers "F.Cu" "F.Mask" "F.Paste")
			(net "FM_PVDDCR_CPU1_P0_OCP_N")
		)
		(pad "G4" smd circle
			(at -5.999988 -3.599942 90)
			(size 0.4064 0.4064)
			(layers "F.Cu" "F.Mask" "F.Paste")
			(net "FM_PVDDCR_CPU1_P1_OCP_N")
		)
		(pad "G5" smd circle
			(at -5.199888 -3.599942 90)
			(size 0.4064 0.4064)
			(layers "F.Cu" "F.Mask" "F.Paste")
			(net "IRQ_SMI_ACTIVE_N_R")
		)
		(pad "G6" smd circle
			(at -4.400042 -3.599942 90)
			(size 0.4064 0.4064)
			(layers "F.Cu" "F.Mask" "F.Paste")
			(net "FM_CPU1_XTRIG_L7")
		)
		(pad "G7" smd circle
			(at -3.599942 -3.599942 90)
			(size 0.4064 0.4064)
			(layers "F.Cu" "F.Mask" "F.Paste")
			(net "FM_CPU1_SA1")
		)
		(pad "G8" smd circle
			(at -2.800096 -3.599942 90)
			(size 0.4064 0.4064)
			(layers "F.Cu" "F.Mask" "F.Paste")
			(net "SGPIO_SCM_INTR_R_N")
		)
		(pad "G9" smd circle
			(at -1.999996 -3.599942 90)
			(size 0.4064 0.4064)
			(layers "F.Cu" "F.Mask" "F.Paste")
			(net "FM_BOARD_BMC_SKU_ID1")
		)
		(pad "G10" smd circle
			(at -1.199896 -3.599942 90)
			(size 0.4064 0.4064)
			(layers "F.Cu" "F.Mask" "F.Paste")
			(net "P3V3_AUX")
		)
		(pad "G11" smd circle
			(at -0.40005 -3.599942 90)
			(size 0.4064 0.4064)
			(layers "F.Cu" "F.Mask" "F.Paste")
			(net "SMB_CPU0_4_XLTR_R_SCL")
		)
		(pad "G12" smd circle
			(at 0.40005 -3.599942 90)
			(size 0.4064 0.4064)
			(layers "F.Cu" "F.Mask" "F.Paste")
			(net "PRSNT_CABLE_GPU_B3_ISO_R_N")
		)
		(pad "G13" smd circle
			(at 1.199896 -3.599942 90)
			(size 0.4064 0.4064)
			(layers "F.Cu" "F.Mask" "F.Paste")
			(net "P3V3_AUX")
		)
		(pad "G14" smd circle
			(at 1.999996 -3.599942 90)
			(size 0.4064 0.4064)
			(layers "F.Cu" "F.Mask" "F.Paste")
			(net "SCM_SPARE_0")
		)
		(pad "G15" smd circle
			(at 2.800096 -3.599942 90)
			(size 0.4064 0.4064)
			(layers "F.Cu" "F.Mask" "F.Paste")
			(net "FM_UARTSW_LSB_N")
		)
		(pad "G16" smd circle
			(at 3.599942 -3.599942 90)
			(size 0.4064 0.4064)
			(layers "F.Cu" "F.Mask" "F.Paste")
			(net "RST_CPU1_PERST1_R_N")
		)
		(pad "G17" smd circle
			(at 4.400042 -3.599942 90)
			(size 0.4064 0.4064)
			(layers "F.Cu" "F.Mask" "F.Paste")
			(net "RST_CPU0_KBRST_N")
		)
		(pad "G18" smd circle
			(at 5.199888 -3.599942 90)
			(size 0.4064 0.4064)
			(layers "F.Cu" "F.Mask" "F.Paste")
			(net "RST_RT_CPU1_P1_RESET_R2_N")
		)
		(pad "G19" smd circle
			(at 5.999988 -3.599942 90)
			(size 0.4064 0.4064)
			(layers "F.Cu" "F.Mask" "F.Paste")
			(net "RST_RT_CPU1_P1_PERST_R2_N")
		)
		(pad "G20" smd circle
			(at 6.800088 -3.599942 90)
			(size 0.4064 0.4064)
			(layers "F.Cu" "F.Mask" "F.Paste")
			(net "FM_CPU0_NV_SAVE_N")
		)
		(pad "G21" smd circle
			(at 7.599934 -3.599942 90)
			(size 0.4064 0.4064)
			(layers "F.Cu" "F.Mask" "F.Paste")
			(net "FM_CPU1_SYS_RESET_N")
		)
		(pad "G22" smd circle
			(at 8.400034 -3.599942 90)
			(size 0.4064 0.4064)
			(layers "F.Cu" "F.Mask" "F.Paste")
			(net "FM_CPU0_RSMRST_N")
		)
		(pad "H1" smd circle
			(at -8.400034 -2.800096 90)
			(size 0.4064 0.4064)
			(layers "F.Cu" "F.Mask" "F.Paste")
			(net "RT_BOARD_ID_ID1")
		)
		(pad "H2" smd circle
			(at -7.599934 -2.800096 90)
			(size 0.4064 0.4064)
			(layers "F.Cu" "F.Mask" "F.Paste")
			(net "CPU0_THERMTRIP_R_N")
		)
		(pad "H3" smd circle
			(at -6.800088 -2.800096 90)
			(size 0.4064 0.4064)
			(layers "F.Cu" "F.Mask" "F.Paste")
			(net "FM_PVDD11_S3_P0_OCP_N")
		)
		(pad "H4" smd circle
			(at -5.999988 -2.800096 90)
			(size 0.4064 0.4064)
			(layers "F.Cu" "F.Mask" "F.Paste")
			(net "FM_PVDD11_S3_P1_OCP_N")
		)
		(pad "H5" smd circle
			(at -5.199888 -2.800096 90)
			(size 0.4064 0.4064)
			(layers "F.Cu" "F.Mask" "F.Paste")
			(net "FM_CPU0_SA0")
		)
		(pad "H6" smd circle
			(at -4.400042 -2.800096 90)
			(size 0.4064 0.4064)
			(layers "F.Cu" "F.Mask" "F.Paste")
			(net "IRQ_TPM_SPI_R1_N")
		)
		(pad "H7" smd circle
			(at -3.599942 -2.800096 90)
			(size 0.4064 0.4064)
			(layers "F.Cu" "F.Mask" "F.Paste")
			(net "IRQ_CPU_BMC_NMI_R_N")
		)
		(pad "H8" smd circle
			(at -2.800096 -2.800096 90)
			(size 0.4064 0.4064)
			(layers "F.Cu" "F.Mask" "F.Paste")
			(net "GND")
		)
		(pad "H9" smd circle
			(at -1.999996 -2.800096 90)
			(size 0.4064 0.4064)
			(layers "F.Cu" "F.Mask" "F.Paste")
			(net "P3V3_AUX")
		)
		(pad "H10" smd circle
			(at -1.199896 -2.800096 90)
			(size 0.4064 0.4064)
			(layers "F.Cu" "F.Mask" "F.Paste")
			(net "GND")
		)
		(pad "H11" smd circle
			(at -0.40005 -2.800096 90)
			(size 0.4064 0.4064)
			(layers "F.Cu" "F.Mask" "F.Paste")
			(net "P3V3_AUX")
		)
	)
)
